(kicad_pcb
	(version 20260206)
	(generator "pcbnew")
	(generator_version "10.0")
	(general
		(thickness 1.6)
		(legacy_teardrops no)
	)
	(paper "A4")
	(title_block
		(title "Bryce Canyon_IOM_IOC_16318-2_OCP.brd")
		(comment 1 "Bryce Canyon / footprints 287-292 of 1605")
	)
	(layers
		(0 "F.Cu" signal "TOP")
		(4 "In1.Cu" signal "L2GND")
		(6 "In2.Cu" signal "L3")
		(8 "In3.Cu" signal "L4VCC")
		(10 "In4.Cu" signal "L5VCC")
		(12 "In5.Cu" signal "L6")
		(14 "In6.Cu" signal "L7GND")
		(2 "B.Cu" signal "BOTTOM")
		(9 "F.Adhes" user "F.Adhesive")
		(11 "B.Adhes" user "B.Adhesive")
		(13 "F.Paste" user "Package Geometry/Pastemask Top")
		(15 "B.Paste" user "Package Geometry/Pastemask Bottom")
		(5 "F.SilkS" user "Ref Des/Silkscreen Top")
		(7 "B.SilkS" user "Ref Des/Silkscreen Bottom")
		(1 "F.Mask" user "Board Geometry/Soldermask Top")
		(3 "B.Mask" user "Board Geometry/Soldermask Bottom")
		(17 "Dwgs.User" user "User.Drawings")
		(19 "Cmts.User" user "User.Comments")
		(21 "Eco1.User" user "User.Eco1")
		(23 "Eco2.User" user "User.Eco2")
		(25 "Edge.Cuts" user "Board Geometry/Outline")
		(27 "Margin" user)
		(31 "F.CrtYd" user "Package Geometry/Place Bound Top")
		(29 "B.CrtYd" user "Package Geometry/Place Bound Bottom")
		(35 "F.Fab" user "Ref Des/Assembly Top")
		(33 "B.Fab" user "Ref Des/Assembly Bottom")
	)
	(footprint ""
		(layer "F.Cu")
		(at 98.711258 -17.90446 90)
		(property "Reference" "L1"
			(at 0 0 90)
			(layer "F.SilkS")
			(hide yes)
			(effects
				(font
					(size 1.27 1.27)
				)
			)
		)
		(property "Value" "DLW21HN900SQ2LGP-U"
			(at -0.0889 -2.7813 90)
			(unlocked yes)
			(layer "F.Fab")
			(hide yes)
			(effects
				(font
					(size 1.016 1.016)
					(thickness 0.1524)
				)
			)
		)
		(property "Device Type" "L2012-4P-1MH40"
			(at -0.0889 -4.3053 90)
			(unlocked yes)
			(layer "F.Fab")
			(hide yes)
			(effects
				(font
					(size 1.016 1.016)
					(thickness 0.1524)
				)
			)
		)
		(duplicate_pad_numbers_are_jumpers no)
		(fp_line
			(start 1.5494 -1.0668)
			(end 1.5494 1.0668)
			(stroke
				(width 0.1524)
				(type default)
			)
			(layer "F.SilkS")
		)
		(fp_line
			(start -1.5494 -1.0668)
			(end 1.5494 -1.0668)
			(stroke
				(width 0.1524)
				(type default)
			)
			(layer "F.SilkS")
		)
		(fp_line
			(start 1.5494 1.0668)
			(end -1.5494 1.0668)
			(stroke
				(width 0.1524)
				(type default)
			)
			(layer "F.SilkS")
		)
		(fp_line
			(start -1.5494 1.0668)
			(end -1.5494 -1.0668)
			(stroke
				(width 0.1524)
				(type default)
			)
			(layer "F.SilkS")
		)
		(fp_line
			(start 1.0668 1.1811)
			(end 0.6858 1.1811)
			(stroke
				(width 0.3302)
				(type default)
			)
			(layer "F.SilkS")
		)
		(fp_poly
			(pts
				(xy 1.500124 1.768856) (xy 0.230124 1.768856) (xy 0.865124 1.133856)
			)
			(stroke
				(width 0)
				(type default)
			)
			(fill yes)
			(layer "F.SilkS")
		)
		(fp_rect
			(start -1.0033 0.5969)
			(end 1.0033 -0.5969)
			(stroke
				(width 0)
				(type default)
			)
			(fill no)
			(layer "F.CrtYd")
		)
		(fp_poly
			(pts
				(xy -1.8034 1.3208) (xy -1.8034 -1.3208) (xy 1.8034 -1.3208) (xy 1.8034 0.0508) (xy 1.0033 0.0508)
				(xy 1.0033 -0.5969) (xy -1.0033 -0.5969) (xy -1.0033 0.5969) (xy 1.0033 0.5969) (xy 1.0033 0.0762)
				(xy 1.8034 0.0762) (xy 1.8034 1.3208)
			)
			(stroke
				(width 0)
				(type default)
			)
			(fill no)
			(layer "F.CrtYd")
		)
		(fp_rect
			(start -1.8034 1.3208)
			(end 1.8034 -1.3208)
			(stroke
				(width 0)
				(type default)
			)
			(fill no)
			(layer "F.Fab")
		)
		(pad "1" smd rect
			(at 0.8382 0.4826 90)
			(size 0.9144 0.6604)
			(layers "F.Cu" "F.Mask" "F.Paste")
			(net "USB_P1_DP")
		)
		(pad "2" smd rect
			(at -0.8382 0.4826 90)
			(size 0.9144 0.6604)
			(layers "F.Cu" "F.Mask" "F.Paste")
			(net "USB_P1_F_DP1")
		)
		(pad "3" smd rect
			(at -0.8382 -0.4826 90)
			(size 0.9144 0.6604)
			(layers "F.Cu" "F.Mask" "F.Paste")
			(net "USB_P1_F_DN1")
		)
		(pad "4" smd rect
			(at 0.8382 -0.4826 90)
			(size 0.9144 0.6604)
			(layers "F.Cu" "F.Mask" "F.Paste")
			(net "USB_P1_DN")
		)
		(zone
			(layer "F.Cu")
			(hatch none 0.5)
			(connect_pads
				(clearance 0)
			)
			(min_thickness 0.25)
			(keepout
				(tracks allowed)
				(vias not_allowed)
				(pads allowed)
				(copperpour not_allowed)
				(footprints allowed)
			)
			(placement
				(enabled no)
				(sheetname "")
			)
			(fill
				(thermal_gap 0.5)
				(thermal_bridge_width 0.5)
				(island_removal_mode 0)
			)
			(polygon
				(pts
					(xy 99.524058 -17.52346) (xy 98.863658 -17.52346) (xy 98.863658 -16.60906) (xy 98.558858 -16.60906)
					(xy 98.558858 -17.52346) (xy 97.898458 -17.52346) (xy 97.898458 -18.28546) (xy 98.558858 -18.28546)
					(xy 98.558858 -19.19986) (xy 98.863658 -19.19986) (xy 98.863658 -18.28546) (xy 99.524058 -18.28546)
				)
			)
		)
		(zone
			(layer "F.Cu")
			(hatch none 0.5)
			(connect_pads
				(clearance 0)
			)
			(min_thickness 0.25)
			(keepout
				(tracks not_allowed)
				(vias allowed)
				(pads allowed)
				(copperpour not_allowed)
				(footprints allowed)
			)
			(placement
				(enabled no)
				(sheetname "")
			)
			(fill
				(thermal_gap 0.5)
				(thermal_bridge_width 0.5)
				(island_removal_mode 0)
			)
			(polygon
				(pts
					(xy 99.524058 -17.52346) (xy 98.863658 -17.52346) (xy 98.863658 -16.60906) (xy 98.558858 -16.60906)
					(xy 98.558858 -17.52346) (xy 97.898458 -17.52346) (xy 97.898458 -18.28546) (xy 98.558858 -18.28546)
					(xy 98.558858 -19.19986) (xy 98.863658 -19.19986) (xy 98.863658 -18.28546) (xy 99.524058 -18.28546)
				)
			)
		)
	)
	(footprint ""
		(layer "F.Cu")
		(at 184.7088 -90.8812)
		(property "Reference" "R641"
			(at 0 0 0)
			(layer "F.SilkS")
			(hide yes)
			(effects
				(font
					(size 1.27 1.27)
				)
			)
		)
		(property "Value" "4K7R2F-GP"
			(at 0.064008 -3.993896 0)
			(unlocked yes)
			(layer "F.Fab")
			(hide yes)
			(effects
				(font
					(size 1.016 1.016)
					(thickness 0.1524)
				)
			)
		)
		(property "Device Type" "R402H16"
			(at 0.064008 -5.517896 0)
			(unlocked yes)
			(layer "F.Fab")
			(hide yes)
			(effects
				(font
					(size 1.016 1.016)
					(thickness 0.1524)
				)
			)
		)
		(duplicate_pad_numbers_are_jumpers no)
		(fp_line
			(start -0.508 -0.9398)
			(end -0.508 0.9398)
			(stroke
				(width 0.1524)
				(type default)
			)
			(layer "F.SilkS")
		)
		(fp_line
			(start 0.508 -0.9398)
			(end -0.508 -0.9398)
			(stroke
				(width 0.1524)
				(type default)
			)
			(layer "F.SilkS")
		)
		(fp_rect
			(start -0.508 0.9398)
			(end 0.508 -0.9398)
			(stroke
				(width 0)
				(type default)
			)
			(fill no)
			(layer "F.CrtYd")
		)
		(fp_rect
			(start -0.508 0.9398)
			(end 0.508 -0.9398)
			(stroke
				(width 0)
				(type default)
			)
			(fill no)
			(layer "F.Fab")
		)
		(pad "1" smd custom
			(at 0 -0.4445)
			(size 0.1397 0.1397)
			(layers "F.Cu" "F.Mask" "F.Paste")
			(net "P1V8")
			(options
				(clearance outline)
				(anchor circle)
			)
			(primitives
				(gr_poly
					(pts
						(arc
							(start -0.1778 -0.2794)
							(mid -0.249642 -0.249642)
							(end -0.2794 -0.1778)
						)
						(arc
							(start -0.2794 0.1778)
							(mid -0.249642 0.249642)
							(end -0.1778 0.2794)
						)
						(arc
							(start 0.1778 0.2794)
							(mid 0.249642 0.249642)
							(end 0.2794 0.1778)
						)
						(arc
							(start 0.2794 -0.1778)
							(mid 0.249642 -0.249642)
							(end 0.1778 -0.2794)
						)
					)
					(width 0)
					(fill yes)
				)
			)
		)
		(pad "2" smd custom
			(at 0 0.4445)
			(size 0.1397 0.1397)
			(layers "F.Cu" "F.Mask" "F.Paste")
			(net "SYS_DBMODE3")
			(options
				(clearance outline)
				(anchor circle)
			)
			(primitives
				(gr_poly
					(pts
						(arc
							(start -0.1778 -0.2794)
							(mid -0.249642 -0.249642)
							(end -0.2794 -0.1778)
						)
						(arc
							(start -0.2794 0.1778)
							(mid -0.249642 0.249642)
							(end -0.1778 0.2794)
						)
						(arc
							(start 0.1778 0.2794)
							(mid 0.249642 0.249642)
							(end 0.2794 0.1778)
						)
						(arc
							(start 0.2794 -0.1778)
							(mid 0.249642 -0.249642)
							(end 0.1778 -0.2794)
						)
					)
					(width 0)
					(fill yes)
				)
			)
		)
	)
	(footprint ""
		(layer "F.Cu")
		(at 226.187 -59.436 90)
		(property "Reference" "SX1"
			(at 0 0 90)
			(layer "F.SilkS")
			(hide yes)
			(effects
				(font
					(size 1.27 1.27)
				)
			)
		)
		(property "Value" "XTAL-25MHZ-295-GP"
			(at -4.4958 -3.3782 90)
			(unlocked yes)
			(layer "F.Fab")
			(hide yes)
			(effects
				(font
					(size 1.016 1.016)
					(thickness 0.1524)
				)
			)
		)
		(property "Device Type" "SMD-OSC38H20"
			(at -4.4958 -4.9022 90)
			(unlocked yes)
			(layer "F.Fab")
			(hide yes)
			(effects
				(font
					(size 1.016 1.016)
					(thickness 0.1524)
				)
			)
		)
		(duplicate_pad_numbers_are_jumpers no)
		(fp_line
			(start 1.5748 -1.1176)
			(end 1.5748 1.1176)
			(stroke
				(width 0.1524)
				(type default)
			)
			(layer "F.SilkS")
		)
		(fp_line
			(start -1.5748 -1.1176)
			(end 1.5748 -1.1176)
			(stroke
				(width 0.1524)
				(type default)
			)
			(layer "F.SilkS")
		)
		(fp_line
			(start 1.5748 1.1176)
			(end -1.5748 1.1176)
			(stroke
				(width 0.1524)
				(type default)
			)
			(layer "F.SilkS")
		)
		(fp_line
			(start -0.659384 1.2065)
			(end -1.668272 1.2065)
			(stroke
				(width 0.3302)
				(type default)
			)
			(layer "F.SilkS")
		)
		(fp_line
			(start -1.668272 1.2065)
			(end -1.668272 0.462788)
			(stroke
				(width 0.3302)
				(type default)
			)
			(layer "F.SilkS")
		)
		(fp_poly
			(pts
				(xy -2.286 1.1557) (xy -2.286 -0.1143) (xy -1.651 0.5207)
			)
			(stroke
				(width 0)
				(type default)
			)
			(fill yes)
			(layer "F.SilkS")
		)
		(fp_rect
			(start -1.0033 0.8001)
			(end 1.0033 -0.8001)
			(stroke
				(width 0)
				(type default)
			)
			(fill no)
			(layer "F.CrtYd")
		)
		(fp_poly
			(pts
				(xy -1.8288 1.3716) (xy -1.8288 -1.3716) (xy 1.8288 -1.3716) (xy 1.8288 -0.0127) (xy 1.0033 -0.0127)
				(xy 1.0033 -0.8001) (xy -1.0033 -0.8001) (xy -1.0033 0.8001) (xy 1.0033 0.8001) (xy 1.0033 0) (xy 1.8288 0)
				(xy 1.8288 1.3716)
			)
			(stroke
				(width 0)
				(type default)
			)
			(fill no)
			(layer "F.CrtYd")
		)
		(fp_rect
			(start -1.8288 1.3716)
			(end 1.8288 -1.3716)
			(stroke
				(width 0)
				(type default)
			)
			(fill no)
			(layer "F.Fab")
		)
		(pad "1" smd rect
			(at -0.769112 0.495046 90)
			(size 1.0922 0.7366)
			(layers "F.Cu" "F.Mask" "F.Paste")
			(net "REF_CLK")
		)
		(pad "2" smd rect
			(at 0.769112 0.495046 90)
			(size 1.0922 0.7366)
			(layers "F.Cu" "F.Mask" "F.Paste")
			(net "GND")
		)
		(pad "3" smd rect
			(at 0.769112 -0.495046 90)
			(size 1.0922 0.7366)
			(layers "F.Cu" "F.Mask" "F.Paste")
			(net "IOC_REF_CLK_P")
		)
		(pad "4" smd rect
			(at -0.769112 -0.495046 90)
			(size 1.0922 0.7366)
			(layers "F.Cu" "F.Mask" "F.Paste")
			(net "GND")
		)
		(zone
			(layer "F.Cu")
			(hatch none 0.5)
			(connect_pads
				(clearance 0)
			)
			(min_thickness 0.25)
			(keepout
				(tracks allowed)
				(vias not_allowed)
				(pads allowed)
				(copperpour not_allowed)
				(footprints allowed)
			)
			(placement
				(enabled no)
				(sheetname "")
			)
			(fill
				(thermal_gap 0.5)
				(thermal_bridge_width 0.5)
				(island_removal_mode 0)
			)
			(polygon
				(pts
					(xy 227.050346 -59.212988) (xy 226.313746 -59.212988) (xy 226.313746 -58.120788) (xy 226.060254 -58.120788)
					(xy 226.060254 -59.212988) (xy 225.323654 -59.212988) (xy 225.323654 -59.659012) (xy 226.060254 -59.659012)
					(xy 226.060254 -60.751212) (xy 226.313746 -60.751212) (xy 226.313746 -59.659012) (xy 227.050346 -59.659012)
				)
			)
		)
		(zone
			(layer "F.Cu")
			(hatch none 0.5)
			(connect_pads
				(clearance 0)
			)
			(min_thickness 0.25)
			(keepout
				(tracks not_allowed)
				(vias allowed)
				(pads allowed)
				(copperpour not_allowed)
				(footprints allowed)
			)
			(placement
				(enabled no)
				(sheetname "")
			)
			(fill
				(thermal_gap 0.5)
				(thermal_bridge_width 0.5)
				(island_removal_mode 0)
			)
			(polygon
				(pts
					(xy 227.050346 -59.212988) (xy 226.313746 -59.212988) (xy 226.313746 -58.120788) (xy 226.060254 -58.120788)
					(xy 226.060254 -59.212988) (xy 225.323654 -59.212988) (xy 225.323654 -59.659012) (xy 226.060254 -59.659012)
					(xy 226.060254 -60.751212) (xy 226.313746 -60.751212) (xy 226.313746 -59.659012) (xy 227.050346 -59.659012)
				)
			)
		)
	)
	(footprint ""
		(layer "F.Cu")
		(at 51.431444 -177.38217 -90)
		(property "Reference" "C49"
			(at 0 0 270)
			(layer "F.SilkS")
			(hide yes)
			(effects
				(font
					(size 1.27 1.27)
				)
			)
		)
		(property "Value" "SCD1U16V2KX-3GP"
			(at 1.1811 -2.7051 270)
			(unlocked yes)
			(layer "F.Fab")
			(hide yes)
			(effects
				(font
					(size 1.016 1.016)
					(thickness 0.1524)
				)
			)
		)
		(property "Device Type" "C402H22"
			(at 1.1811 -4.2291 270)
			(unlocked yes)
			(layer "F.Fab")
			(hide yes)
			(effects
				(font
					(size 1.016 1.016)
					(thickness 0.1524)
				)
			)
		)
		(duplicate_pad_numbers_are_jumpers no)
		(fp_rect
			(start -0.4318 0.9525)
			(end 0.4318 -0.9525)
			(stroke
				(width 0)
				(type default)
			)
			(fill no)
			(layer "F.CrtYd")
		)
		(fp_rect
			(start -0.4318 0.9525)
			(end 0.4318 -0.9525)
			(stroke
				(width 0)
				(type default)
			)
			(fill no)
			(layer "F.Fab")
		)
		(pad "1" smd custom
			(at 0 -0.4445 270)
			(size 0.1524 0.1524)
			(layers "F.Cu" "F.Mask" "F.Paste")
			(net "P3V3_STBY")
			(options
				(clearance outline)
				(anchor circle)
			)
			(primitives
				(gr_poly
					(pts
						(arc
							(start 0.3048 -0.2032)
							(mid 0.275042 -0.275042)
							(end 0.2032 -0.3048)
						)
						(arc
							(start -0.2032 -0.3048)
							(mid -0.275042 -0.275042)
							(end -0.3048 -0.2032)
						)
						(arc
							(start -0.3048 0.2032)
							(mid -0.275042 0.275042)
							(end -0.2032 0.3048)
						)
						(arc
							(start 0.2032 0.3048)
							(mid 0.275042 0.275042)
							(end 0.3048 0.2032)
						)
					)
					(width 0)
					(fill yes)
				)
			)
		)
		(pad "2" smd custom
			(at 0 0.4445 270)
			(size 0.1524 0.1524)
			(layers "F.Cu" "F.Mask" "F.Paste")
			(net "GND")
			(options
				(clearance outline)
				(anchor circle)
			)
			(primitives
				(gr_poly
					(pts
						(arc
							(start 0.3048 -0.2032)
							(mid 0.275042 -0.275042)
							(end 0.2032 -0.3048)
						)
						(arc
							(start -0.2032 -0.3048)
							(mid -0.275042 -0.275042)
							(end -0.3048 -0.2032)
						)
						(arc
							(start -0.3048 0.2032)
							(mid -0.275042 0.275042)
							(end -0.2032 0.3048)
						)
						(arc
							(start 0.2032 0.3048)
							(mid 0.275042 0.275042)
							(end 0.3048 0.2032)
						)
					)
					(width 0)
					(fill yes)
				)
			)
		)
	)
	(footprint ""
		(layer "F.Cu")
		(at 155.1686 -38.481)
		(property "Reference" "TP181"
			(at 0 0 0)
			(layer "F.SilkS")
			(hide yes)
			(effects
				(font
					(size 1.27 1.27)
				)
			)
		)
		(property "Value" "TPAD28-2-GP"
			(at -0.0127 -1.6637 0)
			(unlocked yes)
			(layer "F.Fab")
			(hide yes)
			(effects
				(font
					(size 1.016 1.016)
					(thickness 0.1524)
				)
			)
		)
		(property "Device Type" "TPAD28"
			(at -0.0127 -3.1877 0)
			(unlocked yes)
			(layer "F.Fab")
			(hide yes)
			(effects
				(font
					(size 1.016 1.016)
					(thickness 0.1524)
				)
			)
		)
		(duplicate_pad_numbers_are_jumpers no)
		(fp_poly
			(pts
				(arc
					(start 0.3556 0)
					(mid -0.3556 0)
					(end 0.3556 0)
				)
			)
			(stroke
				(width 0)
				(type default)
			)
			(fill no)
			(layer "F.CrtYd")
		)
		(fp_poly
			(pts
				(arc
					(start 0.6096 0)
					(mid -0.6096 0)
					(end 0.6096 0)
				)
			)
			(stroke
				(width 0)
				(type default)
			)
			(fill no)
			(layer "F.Fab")
		)
		(pad "1" smd circle
			(at 0 0)
			(size 0.7112 0.7112)
			(layers "F.Cu" "F.Mask" "F.Paste")
			(net "ZDEF_EXTB_TP_C2")
		)
	)
	(footprint ""
		(layer "F.Cu")
		(at 44.37761 -131.75488 180)
		(property "Reference" "R158"
			(at 0 0 180)
			(layer "F.SilkS")
			(hide yes)
			(effects
				(font
					(size 1.27 1.27)
				)
			)
		)
		(property "Value" "0R2J-2-GP"
			(at 0.064008 -3.993896 180)
			(unlocked yes)
			(layer "F.Fab")
			(hide yes)
			(effects
				(font
					(size 1.016 1.016)
					(thickness 0.1524)
				)
			)
		)
		(property "Device Type" "R402H16"
			(at 0.064008 -5.517896 180)
			(unlocked yes)
			(layer "F.Fab")
			(hide yes)
			(effects
				(font
					(size 1.016 1.016)
					(thickness 0.1524)
				)
			)
		)
		(duplicate_pad_numbers_are_jumpers no)
		(fp_line
			(start 0.508 -0.9398)
			(end -0.508 -0.9398)
			(stroke
				(width 0.1524)
				(type default)
			)
			(layer "F.SilkS")
		)
		(fp_line
			(start -0.508 -0.9398)
			(end -0.508 0.9398)
			(stroke
				(width 0.1524)
				(type default)
			)
			(layer "F.SilkS")
		)
		(fp_rect
			(start -0.508 0.9398)
			(end 0.508 -0.9398)
			(stroke
				(width 0)
				(type default)
			)
			(fill no)
			(layer "F.CrtYd")
		)
		(fp_rect
			(start -0.508 0.9398)
			(end 0.508 -0.9398)
			(stroke
				(width 0)
				(type default)
			)
			(fill no)
			(layer "F.Fab")
		)
		(pad "1" smd custom
			(at 0 -0.4445 180)
			(size 0.1397 0.1397)
			(layers "F.Cu" "F.Mask" "F.Paste")
			(net "I2C_IOC_SDA")
			(options
				(clearance outline)
				(anchor circle)
			)
			(primitives
				(gr_poly
					(pts
						(arc
							(start -0.1778 -0.2794)
							(mid -0.249642 -0.249642)
							(end -0.2794 -0.1778)
						)
						(arc
							(start -0.2794 0.1778)
							(mid -0.249642 0.249642)
							(end -0.1778 0.2794)
						)
						(arc
							(start 0.1778 0.2794)
							(mid 0.249642 0.249642)
							(end 0.2794 0.1778)
						)
						(arc
							(start 0.2794 -0.1778)
							(mid 0.249642 -0.249642)
							(end 0.1778 -0.2794)
						)
					)
					(width 0)
					(fill yes)
				)
			)
		)
		(pad "2" smd custom
			(at 0 0.4445 180)
			(size 0.1397 0.1397)
			(layers "F.Cu" "F.Mask" "F.Paste")
			(net "BMC_SMB2_DAT")
			(options
				(clearance outline)
				(anchor circle)
			)
			(primitives
				(gr_poly
					(pts
						(arc
							(start -0.1778 -0.2794)
							(mid -0.249642 -0.249642)
							(end -0.2794 -0.1778)
						)
						(arc
							(start -0.2794 0.1778)
							(mid -0.249642 0.249642)
							(end -0.1778 0.2794)
						)
						(arc
							(start 0.1778 0.2794)
							(mid 0.249642 0.249642)
							(end 0.2794 0.1778)
						)
						(arc
							(start 0.2794 -0.1778)
							(mid 0.249642 -0.249642)
							(end 0.1778 -0.2794)
						)
					)
					(width 0)
					(fill yes)
				)
			)
		)
	)
)
